# T6G (Grand Teton) — schematic netlist excerpt (pin names and nets, part order shuffled) for the footprints in the layout excerpt that follows; sources: Cadence DE-HDL packaged netlist, KiCad conversion of 04192023_DAF0TMB3IC0_F0TG_MB_C_brd_V02_OCP.brd

R759  Q_RES  4.7K 5% EMPTY  pkg 0201LF  page 331 : A = P1V8_CPU1_RT_1D ; B = JTAG_TEST_MODE_RT_CPU1_P1
R8098  Q_RES  10K 5% EMPTY  pkg 0402LF  page 147 : A = P3V3_E1S_0_R ; B = P3V3_E1S_PWRGD_0_R1
R2833  Q_RES  100K 1% EMPTY  pkg 0402LF  page 127 : A = FM_SWB_BIC_READY_N ; B = GND

(kicad_pcb
	(version 20260206)
	(generator "pcbnew")
	(generator_version "10.0")
	(general
		(thickness 1.6)
		(legacy_teardrops no)
	)
	(paper "A4")
	(title_block
		(title "04192023_DAF0TMB3IC0_F0TG_MB_C_brd_V02_OCP.brd")
		(comment 1 "Grand Teton / footprints 2080-2082 of 8354")
	)
	(layers
		(0 "F.Cu" signal "TOP")
		(4 "In1.Cu" signal "GND")
		(6 "In2.Cu" signal "IN1")
		(8 "In3.Cu" signal "GND1")
		(10 "In4.Cu" signal "IN2")
		(12 "In5.Cu" signal "GND2")
		(14 "In6.Cu" signal "IN3")
		(16 "In7.Cu" signal "GND3")
		(18 "In8.Cu" signal "VCC")
		(20 "In9.Cu" signal "VCC1")
		(22 "In10.Cu" signal "GND4")
		(24 "In11.Cu" signal "IN4")
		(26 "In12.Cu" signal "GND5")
		(28 "In13.Cu" signal "IN5")
		(30 "In14.Cu" signal "GND6")
		(32 "In15.Cu" signal "IN6")
		(34 "In16.Cu" signal "GND7")
		(2 "B.Cu" signal "BOTTOM")
		(9 "F.Adhes" user "F.Adhesive")
		(11 "B.Adhes" user "B.Adhesive")
		(13 "F.Paste" user "Package Geometry/Pastemask Top")
		(15 "B.Paste" user "Package Geometry/Pastemask Bottom")
		(5 "F.SilkS" user "Ref Des/Silkscreen Top")
		(7 "B.SilkS" user "Ref Des/Silkscreen Bottom")
		(1 "F.Mask" user "Board Geometry/Soldermask Top")
		(3 "B.Mask" user "Board Geometry/Soldermask Bottom")
		(17 "Dwgs.User" user "User.Drawings")
		(19 "Cmts.User" user "User.Comments")
		(21 "Eco1.User" user "User.Eco1")
		(23 "Eco2.User" user "User.Eco2")
		(25 "Edge.Cuts" user "Board Geometry/Outline")
		(27 "Margin" user)
		(31 "F.CrtYd" user "Package Geometry/Place Bound Top")
		(29 "B.CrtYd" user "Package Geometry/Place Bound Bottom")
		(35 "F.Fab" user "Ref Des/Assembly Top")
		(33 "B.Fab" user "Ref Des/Assembly Bottom")
	)
	(footprint ""
		(layer "F.Cu")
		(at 221.361 -80.772 90)
		(property "Reference" "R8098"
			(at 0 0 90)
			(layer "F.SilkS")
			(hide yes)
			(effects
				(font
					(size 1.27 1.27)
				)
			)
		)
		(property "Value" ""
			(at 0 0 90)
			(layer "F.Fab")
			(effects
				(font
					(size 1.27 1.27)
				)
			)
		)
		(duplicate_pad_numbers_are_jumpers no)
		(fp_line
			(start 0.7874 -0.4064)
			(end 0.7874 0.4064)
			(stroke
				(width 0.1524)
				(type default)
			)
			(layer "F.SilkS")
		)
		(fp_line
			(start -0.7874 -0.4064)
			(end 0.7874 -0.4064)
			(stroke
				(width 0.1524)
				(type default)
			)
			(layer "F.SilkS")
		)
		(fp_line
			(start 0.7874 0.4064)
			(end -0.7874 0.4064)
			(stroke
				(width 0.1524)
				(type default)
			)
			(layer "F.SilkS")
		)
		(fp_line
			(start -0.7874 0.4064)
			(end -0.7874 -0.4064)
			(stroke
				(width 0.1524)
				(type default)
			)
			(layer "F.SilkS")
		)
		(fp_line
			(start -0.12065 -0.305054)
			(end -0.12065 -0.2794)
			(stroke
				(width 0.1)
				(type default)
			)
			(layer "F.Fab")
		)
		(fp_line
			(start -0.67945 -0.305054)
			(end -0.12065 -0.305054)
			(stroke
				(width 0.1)
				(type default)
			)
			(layer "F.Fab")
		)
		(fp_line
			(start 0.67945 -0.3048)
			(end 0.67945 0.3048)
			(stroke
				(width 0.1)
				(type default)
			)
			(layer "F.Fab")
		)
		(fp_line
			(start 0.12065 -0.3048)
			(end 0.67945 -0.3048)
			(stroke
				(width 0.1)
				(type default)
			)
			(layer "F.Fab")
		)
		(fp_line
			(start 0.12065 -0.2794)
			(end 0.12065 -0.3048)
			(stroke
				(width 0.1)
				(type default)
			)
			(layer "F.Fab")
		)
		(fp_line
			(start -0.12065 -0.2794)
			(end 0.12065 -0.2794)
			(stroke
				(width 0.1)
				(type default)
			)
			(layer "F.Fab")
		)
		(fp_line
			(start 0.120396 0.2794)
			(end -0.12065 0.2794)
			(stroke
				(width 0.1)
				(type default)
			)
			(layer "F.Fab")
		)
		(fp_line
			(start -0.12065 0.2794)
			(end -0.12065 0.3048)
			(stroke
				(width 0.1)
				(type default)
			)
			(layer "F.Fab")
		)
		(fp_line
			(start 0.67945 0.3048)
			(end 0.120396 0.3048)
			(stroke
				(width 0.1)
				(type default)
			)
			(layer "F.Fab")
		)
		(fp_line
			(start 0.120396 0.3048)
			(end 0.120396 0.2794)
			(stroke
				(width 0.1)
				(type default)
			)
			(layer "F.Fab")
		)
		(fp_line
			(start -0.12065 0.3048)
			(end -0.67945 0.3048)
			(stroke
				(width 0.1)
				(type default)
			)
			(layer "F.Fab")
		)
		(fp_line
			(start -0.67945 0.3048)
			(end -0.67945 -0.305054)
			(stroke
				(width 0.1)
				(type default)
			)
			(layer "F.Fab")
		)
		(pad "1" smd circle
			(at -0.40005 0 90)
			(size 0 0)
			(layers "F.Cu" "F.Mask" "F.Paste")
			(net "P3V3_E1S_0_R")
		)
		(pad "2" smd circle
			(at 0.40005 0 90)
			(size 0 0)
			(layers "F.Cu" "F.Mask" "F.Paste")
			(net "P3V3_E1S_PWRGD_0_R1")
		)
	)
	(footprint ""
		(layer "F.Cu")
		(at 79.114904 -396.491206 -90)
		(property "Reference" "R759"
			(at 0 0 270)
			(layer "F.SilkS")
			(hide yes)
			(effects
				(font
					(size 1.27 1.27)
				)
			)
		)
		(property "Value" ""
			(at 0 0 270)
			(layer "F.Fab")
			(effects
				(font
					(size 1.27 1.27)
				)
			)
		)
		(duplicate_pad_numbers_are_jumpers no)
		(fp_line
			(start -0.32512 0.175006)
			(end -0.32512 -0.175006)
			(stroke
				(width 0.1)
				(type default)
			)
			(layer "F.Fab")
		)
		(fp_line
			(start 0.32512 0.175006)
			(end -0.32512 0.175006)
			(stroke
				(width 0.1)
				(type default)
			)
			(layer "F.Fab")
		)
		(fp_line
			(start -0.32512 -0.175006)
			(end 0.32512 -0.175006)
			(stroke
				(width 0.1)
				(type default)
			)
			(layer "F.Fab")
		)
		(fp_line
			(start 0.32512 -0.175006)
			(end 0.32512 0.175006)
			(stroke
				(width 0.1)
				(type default)
			)
			(layer "F.Fab")
		)
		(pad "1" smd rect
			(at -0.2667 0 270)
			(size 0.3048 0.381)
			(layers "F.Cu" "F.Mask" "F.Paste")
			(net "P1V8_CPU1_RT_1D")
		)
		(pad "2" smd rect
			(at 0.2667 0 90)
			(size 0.3048 0.381)
			(layers "F.Cu" "F.Mask" "F.Paste")
			(net "JTAG_TEST_MODE_RT_CPU1_P1")
		)
	)
	(footprint ""
		(layer "F.Cu")
		(at 428.120302 -436.164736 90)
		(property "Reference" "R2833"
			(at 0 0 90)
			(layer "F.SilkS")
			(hide yes)
			(effects
				(font
					(size 1.27 1.27)
				)
			)
		)
		(property "Value" ""
			(at 0 0 90)
			(layer "F.Fab")
			(effects
				(font
					(size 1.27 1.27)
				)
			)
		)
		(duplicate_pad_numbers_are_jumpers no)
		(fp_line
			(start 0.7874 -0.4064)
			(end 0.7874 0.4064)
			(stroke
				(width 0.1524)
				(type default)
			)
			(layer "F.SilkS")
		)
		(fp_line
			(start -0.7874 -0.4064)
			(end 0.7874 -0.4064)
			(stroke
				(width 0.1524)
				(type default)
			)
			(layer "F.SilkS")
		)
		(fp_line
			(start 0.7874 0.4064)
			(end -0.7874 0.4064)
			(stroke
				(width 0.1524)
				(type default)
			)
			(layer "F.SilkS")
		)
		(fp_line
			(start -0.7874 0.4064)
			(end -0.7874 -0.4064)
			(stroke
				(width 0.1524)
				(type default)
			)
			(layer "F.SilkS")
		)
		(fp_line
			(start -0.12065 -0.305054)
			(end -0.12065 -0.2794)
			(stroke
				(width 0.1)
				(type default)
			)
			(layer "F.Fab")
		)
		(fp_line
			(start -0.67945 -0.305054)
			(end -0.12065 -0.305054)
			(stroke
				(width 0.1)
				(type default)
			)
			(layer "F.Fab")
		)
		(fp_line
			(start 0.67945 -0.3048)
			(end 0.67945 0.3048)
			(stroke
				(width 0.1)
				(type default)
			)
			(layer "F.Fab")
		)
		(fp_line
			(start 0.12065 -0.3048)
			(end 0.67945 -0.3048)
			(stroke
				(width 0.1)
				(type default)
			)
			(layer "F.Fab")
		)
		(fp_line
			(start 0.12065 -0.2794)
			(end 0.12065 -0.3048)
			(stroke
				(width 0.1)
				(type default)
			)
			(layer "F.Fab")
		)
		(fp_line
			(start -0.12065 -0.2794)
			(end 0.12065 -0.2794)
			(stroke
				(width 0.1)
				(type default)
			)
			(layer "F.Fab")
		)
		(fp_line
			(start 0.120396 0.2794)
			(end -0.12065 0.2794)
			(stroke
				(width 0.1)
				(type default)
			)
			(layer "F.Fab")
		)
		(fp_line
			(start -0.12065 0.2794)
			(end -0.12065 0.3048)
			(stroke
				(width 0.1)
				(type default)
			)
			(layer "F.Fab")
		)
		(fp_line
			(start 0.67945 0.3048)
			(end 0.120396 0.3048)
			(stroke
				(width 0.1)
				(type default)
			)
			(layer "F.Fab")
		)
		(fp_line
			(start 0.120396 0.3048)
			(end 0.120396 0.2794)
			(stroke
				(width 0.1)
				(type default)
			)
			(layer "F.Fab")
		)
		(fp_line
			(start -0.12065 0.3048)
			(end -0.67945 0.3048)
			(stroke
				(width 0.1)
				(type default)
			)
			(layer "F.Fab")
		)
		(fp_line
			(start -0.67945 0.3048)
			(end -0.67945 -0.305054)
			(stroke
				(width 0.1)
				(type default)
			)
			(layer "F.Fab")
		)
		(pad "1" smd circle
			(at -0.40005 0 90)
			(size 0 0)
			(layers "F.Cu" "F.Mask" "F.Paste")
			(net "FM_SWB_BIC_READY_N")
		)
		(pad "2" smd circle
			(at 0.40005 0 90)
			(size 0 0)
			(layers "F.Cu" "F.Mask" "F.Paste")
			(net "GND")
		)
	)
)
